(kicad_pcb
	(version 20260206)
	(generator "pcbnew")
	(generator_version "10.0")
	(general
		(thickness 1.6)
		(legacy_teardrops no)
	)
	(paper "A4")
	(title_block
		(title "Wiwynn_Tioga_Pass_MB.brd")
		(comment 1 "Tioga Pass / footprints 3320-3327 of 4770")
	)
	(layers
		(0 "F.Cu" signal "TOP")
		(4 "In1.Cu" signal "L2GND")
		(6 "In2.Cu" signal "L3")
		(8 "In3.Cu" signal "L4GND")
		(10 "In4.Cu" signal "L5")
		(12 "In5.Cu" signal "L6GND")
		(14 "In6.Cu" signal "L7VCC")
		(16 "In7.Cu" signal "L8VCC")
		(18 "In8.Cu" signal "L9GND")
		(20 "In9.Cu" signal "L10")
		(22 "In10.Cu" signal "L11GND")
		(24 "In11.Cu" signal "L12")
		(26 "In12.Cu" signal "L13GND")
		(2 "B.Cu" signal "BOTTOM")
		(9 "F.Adhes" user "F.Adhesive")
		(11 "B.Adhes" user "B.Adhesive")
		(13 "F.Paste" user "Package Geometry/Pastemask Top")
		(15 "B.Paste" user "Package Geometry/Pastemask Bottom")
		(5 "F.SilkS" user "Ref Des/Silkscreen Top")
		(7 "B.SilkS" user "Ref Des/Silkscreen Bottom")
		(1 "F.Mask" user "Board Geometry/Soldermask Top")
		(3 "B.Mask" user "Board Geometry/Soldermask Bottom")
		(17 "Dwgs.User" user "User.Drawings")
		(19 "Cmts.User" user "User.Comments")
		(21 "Eco1.User" user "User.Eco1")
		(23 "Eco2.User" user "User.Eco2")
		(25 "Edge.Cuts" user "Board Geometry/Outline")
		(27 "Margin" user)
		(31 "F.CrtYd" user "Package Geometry/Place Bound Top")
		(29 "B.CrtYd" user "Package Geometry/Place Bound Bottom")
		(35 "F.Fab" user "Ref Des/Assembly Top")
		(33 "B.Fab" user "Ref Des/Assembly Bottom")
	)
	(footprint ""
		(layer "B.Cu")
		(at 39.334694 -106.922316 -90)
		(property "Reference" "R1C2"
			(at 0 0 90)
			(layer "B.SilkS")
			(hide yes)
			(effects
				(font
					(size 1.27 1.27)
				)
				(justify mirror)
			)
		)
		(property "Value" ""
			(at 0 0 90)
			(layer "B.Fab")
			(effects
				(font
					(size 1.27 1.27)
				)
				(justify mirror)
			)
		)
		(duplicate_pad_numbers_are_jumpers no)
		(fp_poly
			(pts
				(xy 0.2794 -0.1016) (xy -0.2794 -0.1016) (xy -0.2794 0.9906) (xy 0.2794 0.9906)
			)
			(stroke
				(width 0)
				(type default)
			)
			(fill no)
			(layer "B.CrtYd")
		)
		(fp_line
			(start -0.2794 0.9906)
			(end -0.2794 -0.1016)
			(stroke
				(width 0.1)
				(type default)
			)
			(layer "B.Fab")
		)
		(fp_line
			(start 0.2794 0.9906)
			(end -0.2794 0.9906)
			(stroke
				(width 0.1)
				(type default)
			)
			(layer "B.Fab")
		)
		(fp_line
			(start -0.2794 -0.1016)
			(end 0.2794 -0.1016)
			(stroke
				(width 0.1)
				(type default)
			)
			(layer "B.Fab")
		)
		(fp_line
			(start 0.2794 -0.1016)
			(end 0.2794 0.9906)
			(stroke
				(width 0.1)
				(type default)
			)
			(layer "B.Fab")
		)
		(pad "1" smd rect
			(at 0 0 90)
			(size 0.508 0.508)
			(layers "B.Cu" "B.Mask" "B.Paste")
			(net "SVID_DIO1_CPU1")
		)
		(pad "2" smd rect
			(at 0 0.889 90)
			(size 0.508 0.508)
			(layers "B.Cu" "B.Mask" "B.Paste")
			(net "SVID_DIO1_CPU1_R")
		)
		(zone
			(layer "B.Cu")
			(hatch none 0.5)
			(connect_pads
				(clearance 0)
			)
			(min_thickness 0.25)
			(keepout
				(tracks not_allowed)
				(vias allowed)
				(pads allowed)
				(copperpour not_allowed)
				(footprints allowed)
			)
			(placement
				(enabled no)
				(sheetname "")
			)
			(fill
				(thermal_gap 0.5)
				(thermal_bridge_width 0.5)
				(island_removal_mode 0)
			)
			(polygon
				(pts
					(xy 38.699694 -106.668316) (xy 38.699694 -107.176316) (xy 39.080694 -107.176316) (xy 39.080694 -106.668316)
				)
			)
		)
		(zone
			(layer "B.Cu")
			(hatch none 0.5)
			(connect_pads
				(clearance 0)
			)
			(min_thickness 0.25)
			(keepout
				(tracks allowed)
				(vias not_allowed)
				(pads allowed)
				(copperpour not_allowed)
				(footprints allowed)
			)
			(placement
				(enabled no)
				(sheetname "")
			)
			(fill
				(thermal_gap 0.5)
				(thermal_bridge_width 0.5)
				(island_removal_mode 0)
			)
			(polygon
				(pts
					(xy 39.080694 -106.668316) (xy 39.080694 -107.176316) (xy 38.699694 -107.176316) (xy 38.699694 -106.668316)
				)
			)
		)
	)
	(footprint ""
		(layer "B.Cu")
		(at 370.1669 -103.6066 90)
		(property "Reference" "C3N30"
			(at 0 0 90)
			(layer "B.SilkS")
			(hide yes)
			(effects
				(font
					(size 1.27 1.27)
				)
				(justify mirror)
			)
		)
		(property "Value" ""
			(at 0 0 90)
			(layer "B.Fab")
			(effects
				(font
					(size 1.27 1.27)
				)
				(justify mirror)
			)
		)
		(duplicate_pad_numbers_are_jumpers no)
		(fp_poly
			(pts
				(xy 0.4953 -0.2032) (xy -0.4953 -0.2032) (xy -0.4953 1.6002) (xy 0.4953 1.6002)
			)
			(stroke
				(width 0)
				(type default)
			)
			(fill no)
			(layer "B.CrtYd")
		)
		(fp_line
			(start 0.4953 -0.2032)
			(end -0.4953 -0.2032)
			(stroke
				(width 0.1)
				(type default)
			)
			(layer "B.Fab")
		)
		(fp_line
			(start -0.4953 -0.2032)
			(end -0.4953 1.6002)
			(stroke
				(width 0.1)
				(type default)
			)
			(layer "B.Fab")
		)
		(fp_line
			(start 0.4953 1.6002)
			(end 0.4953 -0.2032)
			(stroke
				(width 0.1)
				(type default)
			)
			(layer "B.Fab")
		)
		(fp_line
			(start -0.4953 1.6002)
			(end 0.4953 1.6002)
			(stroke
				(width 0.1)
				(type default)
			)
			(layer "B.Fab")
		)
		(pad "1" smd rect
			(at 0 0 270)
			(size 0.762 0.889)
			(layers "B.Cu" "B.Mask" "B.Paste")
			(net "PVNN_PCH_STBY")
		)
		(pad "2" smd rect
			(at 0 1.397 270)
			(size 0.762 0.889)
			(layers "B.Cu" "B.Mask" "B.Paste")
			(net "GND")
		)
		(zone
			(layer "B.Cu")
			(hatch none 0.5)
			(connect_pads
				(clearance 0)
			)
			(min_thickness 0.25)
			(keepout
				(tracks not_allowed)
				(vias allowed)
				(pads allowed)
				(copperpour not_allowed)
				(footprints allowed)
			)
			(placement
				(enabled no)
				(sheetname "")
			)
			(fill
				(thermal_gap 0.5)
				(thermal_bridge_width 0.5)
				(island_removal_mode 0)
			)
			(polygon
				(pts
					(xy 370.6114 -103.9876) (xy 370.6114 -103.2256) (xy 371.1194 -103.2256) (xy 371.1194 -103.9876)
				)
			)
		)
	)
	(footprint ""
		(layer "B.Cu")
		(at 404.3045 -30.099 90)
		(property "Reference" "R25W114"
			(at 0.8382 -0.67818 90)
			(unlocked yes)
			(layer "B.SilkS")
			(effects
				(font
					(size 0.4064 0.254)
					(thickness 0.1524)
				)
				(justify left mirror)
			)
		)
		(property "Value" ""
			(at 0 0 90)
			(layer "B.Fab")
			(effects
				(font
					(size 1.27 1.27)
				)
				(justify mirror)
			)
		)
		(duplicate_pad_numbers_are_jumpers no)
		(fp_poly
			(pts
				(xy 0.2794 -0.1016) (xy -0.2794 -0.1016) (xy -0.2794 0.9906) (xy 0.2794 0.9906)
			)
			(stroke
				(width 0)
				(type default)
			)
			(fill no)
			(layer "B.CrtYd")
		)
		(fp_line
			(start 0.2794 -0.1016)
			(end 0.2794 0.9906)
			(stroke
				(width 0.1)
				(type default)
			)
			(layer "B.Fab")
		)
		(fp_line
			(start -0.2794 -0.1016)
			(end 0.2794 -0.1016)
			(stroke
				(width 0.1)
				(type default)
			)
			(layer "B.Fab")
		)
		(fp_line
			(start 0.2794 0.9906)
			(end -0.2794 0.9906)
			(stroke
				(width 0.1)
				(type default)
			)
			(layer "B.Fab")
		)
		(fp_line
			(start -0.2794 0.9906)
			(end -0.2794 -0.1016)
			(stroke
				(width 0.1)
				(type default)
			)
			(layer "B.Fab")
		)
		(pad "1" smd rect
			(at 0 0 270)
			(size 0.508 0.508)
			(layers "B.Cu" "B.Mask" "B.Paste")
			(net "P3V3_STBY")
		)
		(pad "2" smd rect
			(at 0 0.889 270)
			(size 0.508 0.508)
			(layers "B.Cu" "B.Mask" "B.Paste")
			(net "TP_RGMII1TXD2_GPIOT4")
		)
		(zone
			(layer "B.Cu")
			(hatch none 0.5)
			(connect_pads
				(clearance 0)
			)
			(min_thickness 0.25)
			(keepout
				(tracks allowed)
				(vias not_allowed)
				(pads allowed)
				(copperpour not_allowed)
				(footprints allowed)
			)
			(placement
				(enabled no)
				(sheetname "")
			)
			(fill
				(thermal_gap 0.5)
				(thermal_bridge_width 0.5)
				(island_removal_mode 0)
			)
			(polygon
				(pts
					(xy 404.5585 -30.353) (xy 404.5585 -29.845) (xy 404.9395 -29.845) (xy 404.9395 -30.353)
				)
			)
		)
		(zone
			(layer "B.Cu")
			(hatch none 0.5)
			(connect_pads
				(clearance 0)
			)
			(min_thickness 0.25)
			(keepout
				(tracks not_allowed)
				(vias allowed)
				(pads allowed)
				(copperpour not_allowed)
				(footprints allowed)
			)
			(placement
				(enabled no)
				(sheetname "")
			)
			(fill
				(thermal_gap 0.5)
				(thermal_bridge_width 0.5)
				(island_removal_mode 0)
			)
			(polygon
				(pts
					(xy 404.9395 -30.353) (xy 404.9395 -29.845) (xy 404.5585 -29.845) (xy 404.5585 -30.353)
				)
			)
		)
	)
	(footprint ""
		(layer "B.Cu")
		(at 411.099 -141.0208 -90)
		(property "Reference" "C2L48"
			(at 0 0 90)
			(layer "B.SilkS")
			(hide yes)
			(effects
				(font
					(size 1.27 1.27)
				)
				(justify mirror)
			)
		)
		(property "Value" ""
			(at 0 0 90)
			(layer "B.Fab")
			(effects
				(font
					(size 1.27 1.27)
				)
				(justify mirror)
			)
		)
		(duplicate_pad_numbers_are_jumpers no)
		(fp_poly
			(pts
				(xy -0.3048 -0.1016) (xy -0.3048 0.9906) (xy 0.3048 0.9906) (xy 0.3048 -0.1016)
			)
			(stroke
				(width 0)
				(type default)
			)
			(fill no)
			(layer "B.CrtYd")
		)
		(fp_line
			(start -0.3048 0.9906)
			(end -0.3048 -0.1016)
			(stroke
				(width 0.1)
				(type default)
			)
			(layer "B.Fab")
		)
		(fp_line
			(start 0.3048 0.9906)
			(end -0.3048 0.9906)
			(stroke
				(width 0.1)
				(type default)
			)
			(layer "B.Fab")
		)
		(fp_line
			(start -0.3048 -0.1016)
			(end 0.3048 -0.1016)
			(stroke
				(width 0.1)
				(type default)
			)
			(layer "B.Fab")
		)
		(fp_line
			(start 0.3048 -0.1016)
			(end 0.3048 0.9906)
			(stroke
				(width 0.1)
				(type default)
			)
			(layer "B.Fab")
		)
		(pad "1" smd rect
			(at 0 0 90)
			(size 0.508 0.508)
			(layers "B.Cu" "B.Mask" "B.Paste")
			(net "SATA6G_P6_TX_C_DP")
		)
		(pad "2" smd rect
			(at 0 0.889 90)
			(size 0.508 0.508)
			(layers "B.Cu" "B.Mask" "B.Paste")
			(net "SATA6G_PCH_PCIE_UP_SATA_TXP<6>")
		)
		(zone
			(layer "B.Cu")
			(hatch none 0.5)
			(connect_pads
				(clearance 0)
			)
			(min_thickness 0.25)
			(keepout
				(tracks not_allowed)
				(vias allowed)
				(pads allowed)
				(copperpour not_allowed)
				(footprints allowed)
			)
			(placement
				(enabled no)
				(sheetname "")
			)
			(fill
				(thermal_gap 0.5)
				(thermal_bridge_width 0.5)
				(island_removal_mode 0)
			)
			(polygon
				(pts
					(xy 410.464 -140.7668) (xy 410.464 -141.2748) (xy 410.845 -141.2748) (xy 410.845 -140.7668)
				)
			)
		)
		(zone
			(layer "B.Cu")
			(hatch none 0.5)
			(connect_pads
				(clearance 0)
			)
			(min_thickness 0.25)
			(keepout
				(tracks allowed)
				(vias not_allowed)
				(pads allowed)
				(copperpour not_allowed)
				(footprints allowed)
			)
			(placement
				(enabled no)
				(sheetname "")
			)
			(fill
				(thermal_gap 0.5)
				(thermal_bridge_width 0.5)
				(island_removal_mode 0)
			)
			(polygon
				(pts
					(xy 410.845 -140.7668) (xy 410.845 -141.2748) (xy 410.464 -141.2748) (xy 410.464 -140.7668)
				)
			)
		)
	)
	(footprint ""
		(layer "B.Cu")
		(at 276.5806 -84.5312)
		(property "Reference" "C8W3"
			(at -1.47828 0.78994 90)
			(unlocked yes)
			(layer "B.SilkS")
			(effects
				(font
					(size 0.4064 0.254)
					(thickness 0.1524)
				)
				(justify mirror)
			)
		)
		(property "Value" ""
			(at 0 0 0)
			(layer "B.Fab")
			(effects
				(font
					(size 1.27 1.27)
				)
				(justify mirror)
			)
		)
		(duplicate_pad_numbers_are_jumpers no)
		(fp_poly
			(pts
				(xy 0.7239 -0.2159) (xy -0.7239 -0.2159) (xy -0.7239 1.9939) (xy 0.7239 1.9939)
			)
			(stroke
				(width 0)
				(type default)
			)
			(fill no)
			(layer "B.CrtYd")
		)
		(fp_line
			(start -0.7239 -0.2159)
			(end 0.7239 -0.2159)
			(stroke
				(width 0.1)
				(type default)
			)
			(layer "B.Fab")
		)
		(fp_line
			(start -0.7239 1.9939)
			(end -0.7239 -0.2159)
			(stroke
				(width 0.1)
				(type default)
			)
			(layer "B.Fab")
		)
		(fp_line
			(start 0.7239 -0.2159)
			(end 0.7239 1.9939)
			(stroke
				(width 0.1)
				(type default)
			)
			(layer "B.Fab")
		)
		(fp_line
			(start 0.7239 1.9939)
			(end -0.7239 1.9939)
			(stroke
				(width 0.1)
				(type default)
			)
			(layer "B.Fab")
		)
		(pad "1" smd rect
			(at 0 0 180)
			(size 1.27 1.016)
			(layers "B.Cu" "B.Mask" "B.Paste")
			(net "PVCCIN_CPU0")
		)
		(pad "2" smd rect
			(at 0 1.778 180)
			(size 1.27 1.016)
			(layers "B.Cu" "B.Mask" "B.Paste")
			(net "GND")
		)
		(zone
			(layer "B.Cu")
			(hatch none 0.5)
			(connect_pads
				(clearance 0)
			)
			(min_thickness 0.25)
			(keepout
				(tracks not_allowed)
				(vias allowed)
				(pads allowed)
				(copperpour not_allowed)
				(footprints allowed)
			)
			(placement
				(enabled no)
				(sheetname "")
			)
			(fill
				(thermal_gap 0.5)
				(thermal_bridge_width 0.5)
				(island_removal_mode 0)
			)
			(polygon
				(pts
					(xy 277.2156 -84.0232) (xy 275.9456 -84.0232) (xy 275.9456 -83.2612) (xy 277.2156 -83.2612)
				)
			)
		)
	)
	(footprint ""
		(layer "B.Cu")
		(at 361.444794 -47.258986 -90)
		(property "Reference" "R7D24"
			(at 0 0 90)
			(layer "B.SilkS")
			(hide yes)
			(effects
				(font
					(size 1.27 1.27)
				)
				(justify mirror)
			)
		)
		(property "Value" ""
			(at 0 0 90)
			(layer "B.Fab")
			(effects
				(font
					(size 1.27 1.27)
				)
				(justify mirror)
			)
		)
		(duplicate_pad_numbers_are_jumpers no)
		(fp_poly
			(pts
				(xy 0.2794 -0.1016) (xy -0.2794 -0.1016) (xy -0.2794 0.9906) (xy 0.2794 0.9906)
			)
			(stroke
				(width 0)
				(type default)
			)
			(fill no)
			(layer "B.CrtYd")
		)
		(fp_line
			(start -0.2794 0.9906)
			(end -0.2794 -0.1016)
			(stroke
				(width 0.1)
				(type default)
			)
			(layer "B.Fab")
		)
		(fp_line
			(start 0.2794 0.9906)
			(end -0.2794 0.9906)
			(stroke
				(width 0.1)
				(type default)
			)
			(layer "B.Fab")
		)
		(fp_line
			(start -0.2794 -0.1016)
			(end 0.2794 -0.1016)
			(stroke
				(width 0.1)
				(type default)
			)
			(layer "B.Fab")
		)
		(fp_line
			(start 0.2794 -0.1016)
			(end 0.2794 0.9906)
			(stroke
				(width 0.1)
				(type default)
			)
			(layer "B.Fab")
		)
		(pad "1" smd rect
			(at 0 0 90)
			(size 0.508 0.508)
			(layers "B.Cu" "B.Mask" "B.Paste")
			(net "FM_CPU1_PROCHOT_LVT3_K_N")
		)
		(pad "2" smd rect
			(at 0 0.889 90)
			(size 0.508 0.508)
			(layers "B.Cu" "B.Mask" "B.Paste")
			(net "FM_CPU1_PROCHOT_LVT3_N")
		)
		(zone
			(layer "B.Cu")
			(hatch none 0.5)
			(connect_pads
				(clearance 0)
			)
			(min_thickness 0.25)
			(keepout
				(tracks not_allowed)
				(vias allowed)
				(pads allowed)
				(copperpour not_allowed)
				(footprints allowed)
			)
			(placement
				(enabled no)
				(sheetname "")
			)
			(fill
				(thermal_gap 0.5)
				(thermal_bridge_width 0.5)
				(island_removal_mode 0)
			)
			(polygon
				(pts
					(xy 360.809794 -47.004986) (xy 360.809794 -47.512986) (xy 361.190794 -47.512986) (xy 361.190794 -47.004986)
				)
			)
		)
		(zone
			(layer "B.Cu")
			(hatch none 0.5)
			(connect_pads
				(clearance 0)
			)
			(min_thickness 0.25)
			(keepout
				(tracks allowed)
				(vias not_allowed)
				(pads allowed)
				(copperpour not_allowed)
				(footprints allowed)
			)
			(placement
				(enabled no)
				(sheetname "")
			)
			(fill
				(thermal_gap 0.5)
				(thermal_bridge_width 0.5)
				(island_removal_mode 0)
			)
			(polygon
				(pts
					(xy 361.190794 -47.004986) (xy 361.190794 -47.512986) (xy 360.809794 -47.512986) (xy 360.809794 -47.004986)
				)
			)
		)
	)
	(footprint ""
		(layer "B.Cu")
		(at 401.828 -73.406 180)
		(property "Reference" "R2T53"
			(at 0 0 0)
			(layer "B.SilkS")
			(hide yes)
			(effects
				(font
					(size 1.27 1.27)
				)
				(justify mirror)
			)
		)
		(property "Value" ""
			(at 0 0 0)
			(layer "B.Fab")
			(effects
				(font
					(size 1.27 1.27)
				)
				(justify mirror)
			)
		)
		(duplicate_pad_numbers_are_jumpers no)
		(fp_poly
			(pts
				(xy 0.2794 -0.1016) (xy -0.2794 -0.1016) (xy -0.2794 0.9906) (xy 0.2794 0.9906)
			)
			(stroke
				(width 0)
				(type default)
			)
			(fill no)
			(layer "B.CrtYd")
		)
		(fp_line
			(start 0.2794 0.9906)
			(end -0.2794 0.9906)
			(stroke
				(width 0.1)
				(type default)
			)
			(layer "B.Fab")
		)
		(fp_line
			(start 0.2794 -0.1016)
			(end 0.2794 0.9906)
			(stroke
				(width 0.1)
				(type default)
			)
			(layer "B.Fab")
		)
		(fp_line
			(start -0.2794 0.9906)
			(end -0.2794 -0.1016)
			(stroke
				(width 0.1)
				(type default)
			)
			(layer "B.Fab")
		)
		(fp_line
			(start -0.2794 -0.1016)
			(end 0.2794 -0.1016)
			(stroke
				(width 0.1)
				(type default)
			)
			(layer "B.Fab")
		)
		(pad "1" smd rect
			(at 0 0)
			(size 0.508 0.508)
			(layers "B.Cu" "B.Mask" "B.Paste")
			(net "P3V3_STBY")
		)
		(pad "2" smd rect
			(at 0 0.889)
			(size 0.508 0.508)
			(layers "B.Cu" "B.Mask" "B.Paste")
			(net "SMB_BMC_PMBUS_STBY_LVC3_SDA")
		)
		(zone
			(layer "B.Cu")
			(hatch none 0.5)
			(connect_pads
				(clearance 0)
			)
			(min_thickness 0.25)
			(keepout
				(tracks not_allowed)
				(vias allowed)
				(pads allowed)
				(copperpour not_allowed)
				(footprints allowed)
			)
			(placement
				(enabled no)
				(sheetname "")
			)
			(fill
				(thermal_gap 0.5)
				(thermal_bridge_width 0.5)
				(island_removal_mode 0)
			)
			(polygon
				(pts
					(xy 401.574 -74.041) (xy 402.082 -74.041) (xy 402.082 -73.66) (xy 401.574 -73.66)
				)
			)
		)
		(zone
			(layer "B.Cu")
			(hatch none 0.5)
			(connect_pads
				(clearance 0)
			)
			(min_thickness 0.25)
			(keepout
				(tracks allowed)
				(vias not_allowed)
				(pads allowed)
				(copperpour not_allowed)
				(footprints allowed)
			)
			(placement
				(enabled no)
				(sheetname "")
			)
			(fill
				(thermal_gap 0.5)
				(thermal_bridge_width 0.5)
				(island_removal_mode 0)
			)
			(polygon
				(pts
					(xy 401.574 -73.66) (xy 402.082 -73.66) (xy 402.082 -74.041) (xy 401.574 -74.041)
				)
			)
		)
	)
	(footprint ""
		(layer "B.Cu")
		(at 479.6917 -38.6334 90)
		(property "Reference" "C1R31"
			(at 0 0 90)
			(layer "B.SilkS")
			(hide yes)
			(effects
				(font
					(size 1.27 1.27)
				)
				(justify mirror)
			)
		)
		(property "Value" ""
			(at 0 0 90)
			(layer "B.Fab")
			(effects
				(font
					(size 1.27 1.27)
				)
				(justify mirror)
			)
		)
		(duplicate_pad_numbers_are_jumpers no)
		(fp_poly
			(pts
				(xy -0.3048 -0.1016) (xy -0.3048 0.9906) (xy 0.3048 0.9906) (xy 0.3048 -0.1016)
			)
			(stroke
				(width 0)
				(type default)
			)
			(fill no)
			(layer "B.CrtYd")
		)
		(fp_line
			(start 0.3048 -0.1016)
			(end 0.3048 0.9906)
			(stroke
				(width 0.1)
				(type default)
			)
			(layer "B.Fab")
		)
		(fp_line
			(start -0.3048 -0.1016)
			(end 0.3048 -0.1016)
			(stroke
				(width 0.1)
				(type default)
			)
			(layer "B.Fab")
		)
		(fp_line
			(start 0.3048 0.9906)
			(end -0.3048 0.9906)
			(stroke
				(width 0.1)
				(type default)
			)
			(layer "B.Fab")
		)
		(fp_line
			(start -0.3048 0.9906)
			(end -0.3048 -0.1016)
			(stroke
				(width 0.1)
				(type default)
			)
			(layer "B.Fab")
		)
		(pad "1" smd rect
			(at 0 0 270)
			(size 0.508 0.508)
			(layers "B.Cu" "B.Mask" "B.Paste")
			(net "P1V5_LAN")
		)
		(pad "2" smd rect
			(at 0 0.889 270)
			(size 0.508 0.508)
			(layers "B.Cu" "B.Mask" "B.Paste")
			(net "GND")
		)
		(zone
			(layer "B.Cu")
			(hatch none 0.5)
			(connect_pads
				(clearance 0)
			)
			(min_thickness 0.25)
			(keepout
				(tracks allowed)
				(vias not_allowed)
				(pads allowed)
				(copperpour not_allowed)
				(footprints allowed)
			)
			(placement
				(enabled no)
				(sheetname "")
			)
			(fill
				(thermal_gap 0.5)
				(thermal_bridge_width 0.5)
				(island_removal_mode 0)
			)
			(polygon
				(pts
					(xy 479.9457 -38.8874) (xy 479.9457 -38.3794) (xy 480.3267 -38.3794) (xy 480.3267 -38.8874)
				)
			)
		)
		(zone
			(layer "B.Cu")
			(hatch none 0.5)
			(connect_pads
				(clearance 0)
			)
			(min_thickness 0.25)
			(keepout
				(tracks not_allowed)
				(vias allowed)
				(pads allowed)
				(copperpour not_allowed)
				(footprints allowed)
			)
			(placement
				(enabled no)
				(sheetname "")
			)
			(fill
				(thermal_gap 0.5)
				(thermal_bridge_width 0.5)
				(island_removal_mode 0)
			)
			(polygon
				(pts
					(xy 480.3267 -38.8874) (xy 480.3267 -38.3794) (xy 479.9457 -38.3794) (xy 479.9457 -38.8874)
				)
			)
		)
	)
)
